# S9S_MB_2U (Grand Teton) — schematic netlist excerpt (pin names and nets, part order shuffled) for the footprints in the layout excerpt that follows; sources: Cadence DE-HDL packaged netlist, KiCad conversion of 03242023_DA0F0TMBIJ0_F0T_Motherboard_J_brd_V01_OCP.brd

PR356  Q_RES  2.2 1% CHIP  pkg 0402LF  page 271 : A = PVCCFA_EHV_FIVRA_CPU0_PVCC2 ; B = PVCCFA_EHV_FIVRA_CPU0_VDD2
C483  Q_CAP  47UF 4V 20% X6S  pkg C0805  page 78 : A = PVCCIN_CPU1 ; B = GND
R947  Q_RES  10K 1% CHIP  pkg 0402LF  page 115 : A = P3V3_AUX ; B = PWRGD_FAIL_CPU1_GH_R1

(kicad_pcb
	(version 20260206)
	(generator "pcbnew")
	(generator_version "10.0")
	(general
		(thickness 1.6)
		(legacy_teardrops no)
	)
	(paper "A4")
	(title_block
		(title "03242023_DA0F0TMBIJ0_F0T_Motherboard_J_brd_V01_OCP.brd")
		(comment 1 "Grand Teton / footprints 4604-4606 of 6105")
	)
	(layers
		(0 "F.Cu" signal "TOP")
		(4 "In1.Cu" signal "GND")
		(6 "In2.Cu" signal "IN1")
		(8 "In3.Cu" signal "GND1")
		(10 "In4.Cu" signal "IN2")
		(12 "In5.Cu" signal "GND2")
		(14 "In6.Cu" signal "IN3")
		(16 "In7.Cu" signal "GND3")
		(18 "In8.Cu" signal "VCC")
		(20 "In9.Cu" signal "VCC1")
		(22 "In10.Cu" signal "GND4")
		(24 "In11.Cu" signal "IN4")
		(26 "In12.Cu" signal "GND5")
		(28 "In13.Cu" signal "IN5")
		(30 "In14.Cu" signal "GND6")
		(32 "In15.Cu" signal "IN6")
		(34 "In16.Cu" signal "GND7")
		(2 "B.Cu" signal "BOTTOM")
		(9 "F.Adhes" user "F.Adhesive")
		(11 "B.Adhes" user "B.Adhesive")
		(13 "F.Paste" user "Package Geometry/Pastemask Top")
		(15 "B.Paste" user "Package Geometry/Pastemask Bottom")
		(5 "F.SilkS" user "Ref Des/Silkscreen Top")
		(7 "B.SilkS" user "Ref Des/Silkscreen Bottom")
		(1 "F.Mask" user "Board Geometry/Soldermask Top")
		(3 "B.Mask" user "Board Geometry/Soldermask Bottom")
		(17 "Dwgs.User" user "User.Drawings")
		(19 "Cmts.User" user "User.Comments")
		(21 "Eco1.User" user "User.Eco1")
		(23 "Eco2.User" user "User.Eco2")
		(25 "Edge.Cuts" user "Board Geometry/Outline")
		(27 "Margin" user)
		(31 "F.CrtYd" user "Package Geometry/Place Bound Top")
		(29 "B.CrtYd" user "Package Geometry/Place Bound Bottom")
		(35 "F.Fab" user "Ref Des/Assembly Top")
		(33 "B.Fab" user "Ref Des/Assembly Bottom")
	)
	(footprint ""
		(layer "B.Cu")
		(at 295.565322 -363.78642 -90)
		(property "Reference" "PR356"
			(at 0 0 90)
			(layer "B.SilkS")
			(hide yes)
			(effects
				(font
					(size 1.27 1.27)
				)
				(justify mirror)
			)
		)
		(property "Value" ""
			(at 0 0 90)
			(layer "B.Fab")
			(effects
				(font
					(size 1.27 1.27)
				)
				(justify mirror)
			)
		)
		(duplicate_pad_numbers_are_jumpers no)
		(fp_line
			(start -0.7874 0.4064)
			(end 0.7874 0.4064)
			(stroke
				(width 0.1524)
				(type default)
			)
			(layer "B.SilkS")
		)
		(fp_line
			(start 0.7874 0.4064)
			(end 0.7874 -0.4064)
			(stroke
				(width 0.1524)
				(type default)
			)
			(layer "B.SilkS")
		)
		(fp_line
			(start -0.7874 -0.4064)
			(end -0.7874 0.4064)
			(stroke
				(width 0.1524)
				(type default)
			)
			(layer "B.SilkS")
		)
		(fp_line
			(start 0.7874 -0.4064)
			(end -0.7874 -0.4064)
			(stroke
				(width 0.1524)
				(type default)
			)
			(layer "B.SilkS")
		)
		(fp_line
			(start -0.67945 0.3048)
			(end -0.120396 0.3048)
			(stroke
				(width 0.1)
				(type default)
			)
			(layer "B.Fab")
		)
		(fp_line
			(start -0.120396 0.3048)
			(end -0.120396 0.2794)
			(stroke
				(width 0.1)
				(type default)
			)
			(layer "B.Fab")
		)
		(fp_line
			(start 0.12065 0.3048)
			(end 0.67945 0.3048)
			(stroke
				(width 0.1)
				(type default)
			)
			(layer "B.Fab")
		)
		(fp_line
			(start 0.67945 0.3048)
			(end 0.67945 -0.305054)
			(stroke
				(width 0.1)
				(type default)
			)
			(layer "B.Fab")
		)
		(fp_line
			(start -0.120396 0.2794)
			(end 0.12065 0.2794)
			(stroke
				(width 0.1)
				(type default)
			)
			(layer "B.Fab")
		)
		(fp_line
			(start 0.12065 0.2794)
			(end 0.12065 0.3048)
			(stroke
				(width 0.1)
				(type default)
			)
			(layer "B.Fab")
		)
		(fp_line
			(start -0.12065 -0.2794)
			(end -0.12065 -0.3048)
			(stroke
				(width 0.1)
				(type default)
			)
			(layer "B.Fab")
		)
		(fp_line
			(start 0.12065 -0.2794)
			(end -0.12065 -0.2794)
			(stroke
				(width 0.1)
				(type default)
			)
			(layer "B.Fab")
		)
		(fp_line
			(start -0.67945 -0.3048)
			(end -0.67945 0.3048)
			(stroke
				(width 0.1)
				(type default)
			)
			(layer "B.Fab")
		)
		(fp_line
			(start -0.12065 -0.3048)
			(end -0.67945 -0.3048)
			(stroke
				(width 0.1)
				(type default)
			)
			(layer "B.Fab")
		)
		(fp_line
			(start 0.12065 -0.305054)
			(end 0.12065 -0.2794)
			(stroke
				(width 0.1)
				(type default)
			)
			(layer "B.Fab")
		)
		(fp_line
			(start 0.67945 -0.305054)
			(end 0.12065 -0.305054)
			(stroke
				(width 0.1)
				(type default)
			)
			(layer "B.Fab")
		)
		(pad "1" smd circle
			(at 0.40005 0 90)
			(size 0 0)
			(layers "B.Cu" "B.Mask" "B.Paste")
			(net "PVCCFA_EHV_FIVRA_CPU0_PVCC2")
		)
		(pad "2" smd circle
			(at -0.40005 0 90)
			(size 0 0)
			(layers "B.Cu" "B.Mask" "B.Paste")
			(net "PVCCFA_EHV_FIVRA_CPU0_VDD2")
		)
	)
	(footprint ""
		(layer "B.Cu")
		(at 215.840818 -315.334904 -90)
		(property "Reference" "R947"
			(at 0 0 90)
			(layer "B.SilkS")
			(hide yes)
			(effects
				(font
					(size 1.27 1.27)
				)
				(justify mirror)
			)
		)
		(property "Value" ""
			(at 0 0 90)
			(layer "B.Fab")
			(effects
				(font
					(size 1.27 1.27)
				)
				(justify mirror)
			)
		)
		(duplicate_pad_numbers_are_jumpers no)
		(fp_line
			(start -0.7874 0.4064)
			(end 0.7874 0.4064)
			(stroke
				(width 0.1524)
				(type default)
			)
			(layer "B.SilkS")
		)
		(fp_line
			(start 0.7874 0.4064)
			(end 0.7874 -0.4064)
			(stroke
				(width 0.1524)
				(type default)
			)
			(layer "B.SilkS")
		)
		(fp_line
			(start -0.7874 -0.4064)
			(end -0.7874 0.4064)
			(stroke
				(width 0.1524)
				(type default)
			)
			(layer "B.SilkS")
		)
		(fp_line
			(start 0.7874 -0.4064)
			(end -0.7874 -0.4064)
			(stroke
				(width 0.1524)
				(type default)
			)
			(layer "B.SilkS")
		)
		(fp_line
			(start -0.67945 0.3048)
			(end -0.120396 0.3048)
			(stroke
				(width 0.1)
				(type default)
			)
			(layer "B.Fab")
		)
		(fp_line
			(start -0.120396 0.3048)
			(end -0.120396 0.2794)
			(stroke
				(width 0.1)
				(type default)
			)
			(layer "B.Fab")
		)
		(fp_line
			(start 0.12065 0.3048)
			(end 0.67945 0.3048)
			(stroke
				(width 0.1)
				(type default)
			)
			(layer "B.Fab")
		)
		(fp_line
			(start 0.67945 0.3048)
			(end 0.67945 -0.305054)
			(stroke
				(width 0.1)
				(type default)
			)
			(layer "B.Fab")
		)
		(fp_line
			(start -0.120396 0.2794)
			(end 0.12065 0.2794)
			(stroke
				(width 0.1)
				(type default)
			)
			(layer "B.Fab")
		)
		(fp_line
			(start 0.12065 0.2794)
			(end 0.12065 0.3048)
			(stroke
				(width 0.1)
				(type default)
			)
			(layer "B.Fab")
		)
		(fp_line
			(start -0.12065 -0.2794)
			(end -0.12065 -0.3048)
			(stroke
				(width 0.1)
				(type default)
			)
			(layer "B.Fab")
		)
		(fp_line
			(start 0.12065 -0.2794)
			(end -0.12065 -0.2794)
			(stroke
				(width 0.1)
				(type default)
			)
			(layer "B.Fab")
		)
		(fp_line
			(start -0.67945 -0.3048)
			(end -0.67945 0.3048)
			(stroke
				(width 0.1)
				(type default)
			)
			(layer "B.Fab")
		)
		(fp_line
			(start -0.12065 -0.3048)
			(end -0.67945 -0.3048)
			(stroke
				(width 0.1)
				(type default)
			)
			(layer "B.Fab")
		)
		(fp_line
			(start 0.12065 -0.305054)
			(end 0.12065 -0.2794)
			(stroke
				(width 0.1)
				(type default)
			)
			(layer "B.Fab")
		)
		(fp_line
			(start 0.67945 -0.305054)
			(end 0.12065 -0.305054)
			(stroke
				(width 0.1)
				(type default)
			)
			(layer "B.Fab")
		)
		(pad "1" smd circle
			(at 0.40005 0 90)
			(size 0 0)
			(layers "B.Cu" "B.Mask" "B.Paste")
			(net "P3V3_AUX")
		)
		(pad "2" smd circle
			(at -0.40005 0 90)
			(size 0 0)
			(layers "B.Cu" "B.Mask" "B.Paste")
			(net "PWRGD_FAIL_CPU1_GH_R1")
		)
	)
	(footprint ""
		(layer "B.Cu")
		(at 105.726738 -241.19459 90)
		(property "Reference" "C483"
			(at 0 0 90)
			(layer "B.SilkS")
			(hide yes)
			(effects
				(font
					(size 1.27 1.27)
				)
				(justify mirror)
			)
		)
		(property "Value" ""
			(at 0 0 90)
			(layer "B.Fab")
			(effects
				(font
					(size 1.27 1.27)
				)
				(justify mirror)
			)
		)
		(duplicate_pad_numbers_are_jumpers no)
		(fp_line
			(start 1.524 -0.762)
			(end -1.524 -0.762)
			(stroke
				(width 0.1524)
				(type default)
			)
			(layer "B.SilkS")
		)
		(fp_line
			(start -1.524 -0.762)
			(end -1.524 0.762)
			(stroke
				(width 0.1524)
				(type default)
			)
			(layer "B.SilkS")
		)
		(fp_line
			(start 1.524 0.762)
			(end 1.524 -0.762)
			(stroke
				(width 0.1524)
				(type default)
			)
			(layer "B.SilkS")
		)
		(fp_line
			(start -1.524 0.762)
			(end 1.524 0.762)
			(stroke
				(width 0.1524)
				(type default)
			)
			(layer "B.SilkS")
		)
		(fp_line
			(start 1.1049 -0.724916)
			(end 1.1049 0.724916)
			(stroke
				(width 0.1)
				(type default)
			)
			(layer "B.Fab")
		)
		(fp_line
			(start -1.1049 -0.724916)
			(end 1.1049 -0.724916)
			(stroke
				(width 0.1)
				(type default)
			)
			(layer "B.Fab")
		)
		(fp_line
			(start 1.1049 0.724916)
			(end -1.1049 0.724916)
			(stroke
				(width 0.1)
				(type default)
			)
			(layer "B.Fab")
		)
		(fp_line
			(start -1.1049 0.724916)
			(end -1.1049 -0.724916)
			(stroke
				(width 0.1)
				(type default)
			)
			(layer "B.Fab")
		)
		(pad "1" smd rect
			(at 0.889 0 90)
			(size 1.016 1.27)
			(layers "B.Cu" "B.Mask" "B.Paste")
			(net "PVCCIN_CPU1")
		)
		(pad "2" smd rect
			(at -0.889 0 90)
			(size 1.016 1.27)
			(layers "B.Cu" "B.Mask" "B.Paste")
			(net "GND")
		)
	)
)
